(kicad_pcb
	(version 20260206)
	(generator "pcbnew")
	(generator_version "10.0")
	(general
		(thickness 1.6)
		(legacy_teardrops no)
	)
	(paper "A4")
	(title_block
		(title "pdpb — Lightning_PDPB_BRD.brd")
		(comment 1 "Lightning (Wiwynn / Facebook NVMe JBOF) / footprints 148-148 of 1140")
	)
	(layers
		(0 "F.Cu" signal "TOP")
		(4 "In1.Cu" signal "L2GND")
		(6 "In2.Cu" signal "L3")
		(8 "In3.Cu" signal "L4VCC")
		(10 "In4.Cu" signal "L5VCC")
		(12 "In5.Cu" signal "L6")
		(14 "In6.Cu" signal "L7GND")
		(2 "B.Cu" signal "BOTTOM")
		(9 "F.Adhes" user "F.Adhesive")
		(11 "B.Adhes" user "B.Adhesive")
		(13 "F.Paste" user "Package Geometry/Pastemask Top")
		(15 "B.Paste" user "Package Geometry/Pastemask Bottom")
		(5 "F.SilkS" user "Ref Des/Silkscreen Top")
		(7 "B.SilkS" user "Ref Des/Silkscreen Bottom")
		(1 "F.Mask" user "Board Geometry/Soldermask Top")
		(3 "B.Mask" user "Board Geometry/Soldermask Bottom")
		(17 "Dwgs.User" user "User.Drawings")
		(19 "Cmts.User" user "User.Comments")
		(21 "Eco1.User" user "User.Eco1")
		(23 "Eco2.User" user "User.Eco2")
		(25 "Edge.Cuts" user "Board Geometry/Outline")
		(27 "Margin" user)
		(31 "F.CrtYd" user "Package Geometry/Place Bound Top")
		(29 "B.CrtYd" user "Package Geometry/Place Bound Bottom")
		(35 "F.Fab" user "Ref Des/Assembly Top")
		(33 "B.Fab" user "Ref Des/Assembly Bottom")
	)
	(footprint ""
		(layer "F.Cu")
		(at 226.149916 -170.669966 90)
		(property "Reference" "J3"
			(at 0 0 90)
			(layer "F.SilkS")
			(hide yes)
			(effects
				(font
					(size 1.27 1.27)
				)
			)
		)
		(property "Value" "PCISLT68-14-GP-U1"
			(at -22.225 12.7508 90)
			(unlocked yes)
			(layer "F.Fab")
			(hide yes)
			(effects
				(font
					(size 1.016 1.016)
					(thickness 0.1524)
				)
			)
		)
		(property "Device Type" "SD-78827-0001"
			(at -22.225 11.2268 90)
			(unlocked yes)
			(layer "F.Fab")
			(hide yes)
			(effects
				(font
					(size 1.016 1.016)
					(thickness 0.1524)
				)
			)
		)
		(duplicate_pad_numbers_are_jumpers no)
		(fp_line
			(start 20.4724 -3.4036)
			(end 20.4724 0.0254)
			(stroke
				(width 0.1524)
				(type default)
			)
			(layer "F.SilkS")
		)
		(fp_line
			(start -20.4724 -3.4036)
			(end 20.4724 -3.4036)
			(stroke
				(width 0.1524)
				(type default)
			)
			(layer "F.SilkS")
		)
		(fp_line
			(start 23.749 0.0254)
			(end 23.749 4.6736)
			(stroke
				(width 0.1524)
				(type default)
			)
			(layer "F.SilkS")
		)
		(fp_line
			(start 20.4724 0.0254)
			(end 23.749 0.0254)
			(stroke
				(width 0.1524)
				(type default)
			)
			(layer "F.SilkS")
		)
		(fp_line
			(start -20.4724 0.0254)
			(end -20.4724 -3.4036)
			(stroke
				(width 0.1524)
				(type default)
			)
			(layer "F.SilkS")
		)
		(fp_line
			(start -23.749 0.0254)
			(end -20.4724 0.0254)
			(stroke
				(width 0.1524)
				(type default)
			)
			(layer "F.SilkS")
		)
		(fp_line
			(start 23.117556 1.803908)
			(end 23.117556 2.896108)
			(stroke
				(width 0.3048)
				(type default)
			)
			(layer "F.SilkS")
		)
		(fp_line
			(start -20.882356 1.803908)
			(end -20.882356 2.896108)
			(stroke
				(width 0.3048)
				(type default)
			)
			(layer "F.SilkS")
		)
		(fp_line
			(start 20.882356 2.896108)
			(end 20.882356 1.803908)
			(stroke
				(width 0.3048)
				(type default)
			)
			(layer "F.SilkS")
		)
		(fp_line
			(start -23.117556 2.896108)
			(end -23.117556 1.803908)
			(stroke
				(width 0.3048)
				(type default)
			)
			(layer "F.SilkS")
		)
		(fp_line
			(start 23.749 4.6736)
			(end 20.4724 4.6736)
			(stroke
				(width 0.1524)
				(type default)
			)
			(layer "F.SilkS")
		)
		(fp_line
			(start 20.4724 4.6736)
			(end 20.4724 12.0142)
			(stroke
				(width 0.1524)
				(type default)
			)
			(layer "F.SilkS")
		)
		(fp_line
			(start -20.4724 4.6736)
			(end -23.749 4.6736)
			(stroke
				(width 0.1524)
				(type default)
			)
			(layer "F.SilkS")
		)
		(fp_line
			(start -23.749 4.6736)
			(end -23.749 0.0254)
			(stroke
				(width 0.1524)
				(type default)
			)
			(layer "F.SilkS")
		)
		(fp_line
			(start 17.8435 10.3124)
			(end -17.8435 10.3124)
			(stroke
				(width 0.1524)
				(type default)
			)
			(layer "F.SilkS")
		)
		(fp_line
			(start -17.8435 10.3124)
			(end -17.8435 12.0142)
			(stroke
				(width 0.1524)
				(type default)
			)
			(layer "F.SilkS")
		)
		(fp_line
			(start 20.4724 12.0142)
			(end 17.8435 12.0142)
			(stroke
				(width 0.1524)
				(type default)
			)
			(layer "F.SilkS")
		)
		(fp_line
			(start 17.8435 12.0142)
			(end 17.8435 10.3124)
			(stroke
				(width 0.1524)
				(type default)
			)
			(layer "F.SilkS")
		)
		(fp_line
			(start -17.8435 12.0142)
			(end -20.4724 12.0142)
			(stroke
				(width 0.1524)
				(type default)
			)
			(layer "F.SilkS")
		)
		(fp_line
			(start -20.4724 12.0142)
			(end -20.4724 4.6736)
			(stroke
				(width 0.1524)
				(type default)
			)
			(layer "F.SilkS")
		)
		(fp_arc
			(start 20.882356 1.803908)
			(mid 21.999956 0.686308)
			(end 23.117556 1.803908)
			(stroke
				(width 0.3048)
				(type default)
			)
			(layer "F.SilkS")
		)
		(fp_arc
			(start -23.117556 1.803908)
			(mid -21.999956 0.686308)
			(end -20.882356 1.803908)
			(stroke
				(width 0.3048)
				(type default)
			)
			(layer "F.SilkS")
		)
		(fp_arc
			(start 23.117556 2.896108)
			(mid 21.999956 4.013708)
			(end 20.882356 2.896108)
			(stroke
				(width 0.3048)
				(type default)
			)
			(layer "F.SilkS")
		)
		(fp_arc
			(start -20.882356 2.896108)
			(mid -21.999956 4.013708)
			(end -23.117556 2.896108)
			(stroke
				(width 0.3048)
				(type default)
			)
			(layer "F.SilkS")
		)
		(fp_poly
			(pts
				(xy -20.2184 11.7602) (xy -20.2184 4.4196) (xy -23.495 4.4196) (xy -23.495 0.2794) (xy -20.2184 0.2794)
				(xy -20.2184 -3.1496) (xy 20.2184 -3.1496) (xy 20.2184 0.2794) (xy 23.495 0.2794) (xy 23.495 4.4196)
				(xy 20.2184 4.4196) (xy 20.2184 11.7602) (xy 18.0975 11.7602) (xy 18.0975 10.0584) (xy -18.0975 10.0584)
				(xy -18.0975 11.7602)
			)
			(stroke
				(width 0)
				(type default)
			)
			(fill no)
			(layer "F.CrtYd")
		)
		(fp_poly
			(pts
				(xy -21.2471 16.256) (xy -21.2471 4.9276) (xy -24.003 4.9276) (xy -24.003 -0.2286) (xy -20.7264 -0.2286)
				(xy -20.7264 -3.6576) (xy 20.7264 -3.6576) (xy 20.7264 -0.2286) (xy 24.003 -0.2286) (xy 24.003 -0.00635)
				(xy 20.2184 -0.00635) (xy 20.2184 -3.1496) (xy -20.2184 -3.1496) (xy -20.2184 0.2794) (xy -23.495 0.2794)
				(xy -23.495 4.4196) (xy -20.2184 4.4196) (xy -20.2184 11.7602) (xy -18.0975 11.7602) (xy -18.0975 10.0584)
				(xy 18.0975 10.0584) (xy 18.0975 11.7602) (xy 20.2184 11.7602) (xy 20.2184 4.4196) (xy 23.495 4.4196)
				(xy 23.495 0.2794) (xy 20.2184 0.2794) (xy 20.2184 0.00635) (xy 24.003 0.00635) (xy 24.003 4.9276)
				(xy 21.2471 4.9276) (xy 21.2471 16.256)
			)
			(stroke
				(width 0)
				(type default)
			)
			(fill no)
			(layer "F.CrtYd")
		)
		(fp_poly
			(pts
				(xy -21.2471 16.256) (xy -21.2471 4.9276) (xy -24.003 4.9276) (xy -24.003 -0.2286) (xy -20.7264 -0.2286)
				(xy -20.7264 -3.6576) (xy 20.7264 -3.6576) (xy 20.7264 -0.2286) (xy 24.003 -0.2286) (xy 24.003 4.9276)
				(xy 21.2471 4.9276) (xy 21.2471 16.256)
			)
			(stroke
				(width 0)
				(type default)
			)
			(fill no)
			(layer "F.Fab")
		)
		(pad "" np_thru_hole circle
			(at -18.999962 0 90)
			(size 0.254 0.254)
			(drill 1.8542)
			(layers "*.Cu" "*.Mask")
			(clearance 1.1557)
			(thermal_gap 1.1557)
		)
		(pad "" np_thru_hole circle
			(at 18.999962 0 90)
			(size 0.254 0.254)
			(drill 1.8542)
			(layers "*.Cu" "*.Mask")
			(clearance 1.1557)
			(thermal_gap 1.1557)
		)
		(pad "E1" smd rect
			(at -7.079996 1.240028 90)
			(size 0.508 2.0066)
			(layers "F.Cu" "F.Mask" "F.Paste")
			(net "PE_CLK100M_DR3_2_P")
		)
		(pad "E2" smd rect
			(at -6.279896 1.240028 90)
			(size 0.508 2.0066)
			(layers "F.Cu" "F.Mask" "F.Paste")
			(net "PE_CLK100M_DR3_2_N")
		)
		(pad "E3" smd rect
			(at -5.48005 1.240028 90)
			(size 0.508 2.0066)
			(layers "F.Cu" "F.Mask" "F.Paste")
			(net "P3V3")
		)
		(pad "E4" smd rect
			(at -4.67995 1.240028 90)
			(size 0.508 2.0066)
			(layers "F.Cu" "F.Mask" "F.Paste")
			(net "SSD3_PERST_N")
		)
		(pad "E5" smd rect
			(at -3.880104 1.240028 90)
			(size 0.508 2.0066)
			(layers "F.Cu" "F.Mask" "F.Paste")
			(net "SSD3_PERST_N")
		)
		(pad "E6" smd rect
			(at -3.080004 1.240028 90)
			(size 0.508 2.0066)
			(layers "F.Cu" "F.Mask" "F.Paste")
			(net "Net_1179")
		)
		(pad "E7" smd rect
			(at -15.48003 -1.949958 90)
			(size 0.508 2.0066)
			(layers "F.Cu" "F.Mask" "F.Paste")
			(net "PE_CLK100M_DR3_1_P")
		)
		(pad "E8" smd rect
			(at -14.67993 -1.949958 90)
			(size 0.508 2.0066)
			(layers "F.Cu" "F.Mask" "F.Paste")
			(net "PE_CLK100M_DR3_1_N")
		)
		(pad "E9" smd rect
			(at -13.880084 -1.949958 90)
			(size 0.508 2.0066)
			(layers "F.Cu" "F.Mask" "F.Paste")
			(net "GND")
		)
		(pad "E10" smd rect
			(at -13.079984 -1.949958 90)
			(size 0.508 2.0066)
			(layers "F.Cu" "F.Mask" "F.Paste")
			(net "PE_TX1_DR3_N")
		)
		(pad "E11" smd rect
			(at -12.279884 -1.949958 90)
			(size 0.508 2.0066)
			(layers "F.Cu" "F.Mask" "F.Paste")
			(net "PE_TX1_DR3_P")
		)
		(pad "E12" smd rect
			(at -11.480038 -1.949958 90)
			(size 0.508 2.0066)
			(layers "F.Cu" "F.Mask" "F.Paste")
			(net "GND")
		)
		(pad "E13" smd rect
			(at -10.679938 -1.949958 90)
			(size 0.508 2.0066)
			(layers "F.Cu" "F.Mask" "F.Paste")
			(net "PE_RX1_DR3_N")
		)
		(pad "E14" smd rect
			(at -9.880092 -1.949958 90)
			(size 0.508 2.0066)
			(layers "F.Cu" "F.Mask" "F.Paste")
			(net "PE_RX1_DR3_P")
		)
		(pad "E15" smd rect
			(at -9.079992 -1.949958 90)
			(size 0.508 2.0066)
			(layers "F.Cu" "F.Mask" "F.Paste")
			(net "GND")
		)
		(pad "E16" smd rect
			(at -8.279892 -1.949958 90)
			(size 0.508 2.0066)
			(layers "F.Cu" "F.Mask" "F.Paste")
			(net "Net_1186")
		)
		(pad "E17" smd rect
			(at 9.320022 -1.949958 90)
			(size 0.508 2.0066)
			(layers "F.Cu" "F.Mask" "F.Paste")
			(net "PE_TX4_DR3_N")
		)
		(pad "E18" smd rect
			(at 10.120122 -1.949958 90)
			(size 0.508 2.0066)
			(layers "F.Cu" "F.Mask" "F.Paste")
			(net "PE_TX4_DR3_P")
		)
		(pad "E19" smd rect
			(at 10.919968 -1.949958 90)
			(size 0.508 2.0066)
			(layers "F.Cu" "F.Mask" "F.Paste")
			(net "GND")
		)
		(pad "E20" smd rect
			(at 11.720068 -1.949958 90)
			(size 0.508 2.0066)
			(layers "F.Cu" "F.Mask" "F.Paste")
			(net "PE_RX4_DR3_N")
		)
		(pad "E21" smd rect
			(at 12.519914 -1.949958 90)
			(size 0.508 2.0066)
			(layers "F.Cu" "F.Mask" "F.Paste")
			(net "PE_RX4_DR3_P")
		)
		(pad "E22" smd rect
			(at 13.320014 -1.949958 90)
			(size 0.508 2.0066)
			(layers "F.Cu" "F.Mask" "F.Paste")
			(net "GND")
		)
		(pad "E23" smd rect
			(at 14.120114 -1.949958 90)
			(size 0.508 2.0066)
			(layers "F.Cu" "F.Mask" "F.Paste")
			(net "SCL_DR3_R")
		)
		(pad "E24" smd rect
			(at 14.91996 -1.949958 90)
			(size 0.508 2.0066)
			(layers "F.Cu" "F.Mask" "F.Paste")
			(net "SDA_DR3_R")
		)
		(pad "E25" smd rect
			(at 15.72006 -1.949958 90)
			(size 0.508 2.0066)
			(layers "F.Cu" "F.Mask" "F.Paste")
			(net "DUALPORTEN#3")
		)
		(pad "P1" smd rect
			(at -1.905 0.824992 90)
			(size 0.6604 2.0574)
			(layers "F.Cu" "F.Mask" "F.Paste")
			(net "Net_1182")
		)
		(pad "P2" smd rect
			(at -0.635 0.824992 90)
			(size 0.6604 2.0574)
			(layers "F.Cu" "F.Mask" "F.Paste")
			(net "Net_1181")
		)
		(pad "P3" smd rect
			(at 0.635 0.824992 90)
			(size 0.6604 2.0574)
			(layers "F.Cu" "F.Mask" "F.Paste")
			(net "Net_1180")
		)
		(pad "P4" smd rect
			(at 1.905 0.824992 90)
			(size 0.6604 2.0574)
			(layers "F.Cu" "F.Mask" "F.Paste")
			(net "SSD3_CLK0_OE_N")
		)
		(pad "P5" smd rect
			(at 3.175 0.824992 90)
			(size 0.6604 2.0574)
			(layers "F.Cu" "F.Mask" "F.Paste")
			(net "GND")
		)
		(pad "P6" smd rect
			(at 4.445 0.824992 90)
			(size 0.6604 2.0574)
			(layers "F.Cu" "F.Mask" "F.Paste")
			(net "GND")
		)
		(pad "P7" smd rect
			(at 5.715 0.824992 90)
			(size 0.6604 2.0574)
			(layers "F.Cu" "F.Mask" "F.Paste")
			(net "Net_92")
		)
		(pad "P8" smd rect
			(at 6.985 0.824992 90)
			(size 0.6604 2.0574)
			(layers "F.Cu" "F.Mask" "F.Paste")
			(net "Net_64")
		)
		(pad "P9" smd rect
			(at 8.255 0.824992 90)
			(size 0.6604 2.0574)
			(layers "F.Cu" "F.Mask" "F.Paste")
			(net "Net_78")
		)
		(pad "P10" smd rect
			(at 9.525 0.824992 90)
			(size 0.6604 2.0574)
			(layers "F.Cu" "F.Mask" "F.Paste")
			(net "SSD_PRSNT_NET3")
		)
		(pad "P11" smd rect
			(at 10.795 0.824992 90)
			(size 0.6604 2.0574)
			(layers "F.Cu" "F.Mask" "F.Paste")
			(net "SSD_ACT_DR3")
		)
		(pad "P12" smd rect
			(at 12.065 0.824992 90)
			(size 0.6604 2.0574)
			(layers "F.Cu" "F.Mask" "F.Paste")
			(net "GND")
		)
		(pad "P13" smd rect
			(at 13.335 0.824992 90)
			(size 0.6604 2.0574)
			(layers "F.Cu" "F.Mask" "F.Paste")
			(net "12V_PRECH_SSD3")
		)
		(pad "P14" smd rect
			(at 14.605 0.824992 90)
			(size 0.6604 2.0574)
			(layers "F.Cu" "F.Mask" "F.Paste")
			(net "P12V_SSD3")
		)
		(pad "P15" smd rect
			(at 15.875 0.824992 90)
			(size 0.6604 2.0574)
			(layers "F.Cu" "F.Mask" "F.Paste")
			(net "P12V_SSD3")
		)
		(pad "PTH1" thru_hole oval
			(at -21.999956 2.350008 90)
			(size 1.524 2.6162)
			(drill oval 0.8128 1.905)
			(layers "*.Cu" "*.Mask")
			(remove_unused_layers no)
			(net "Net_1191")
			(clearance 0.1524)
			(thermal_gap 0.1524)
		)
		(pad "PTH2" thru_hole oval
			(at 21.999956 2.350008 90)
			(size 1.524 2.6162)
			(drill oval 0.8128 1.905)
			(layers "*.Cu" "*.Mask")
			(remove_unused_layers no)
			(net "Net_1175")
			(clearance 0.1524)
			(thermal_gap 0.1524)
		)
		(pad "S1" smd rect
			(at -15.875 0.824992 90)
			(size 0.6604 2.0574)
			(layers "F.Cu" "F.Mask" "F.Paste")
			(net "GND")
		)
		(pad "S2" smd rect
			(at -14.605 0.824992 90)
			(size 0.6604 2.0574)
			(layers "F.Cu" "F.Mask" "F.Paste")
			(net "Net_1190")
		)
		(pad "S3" smd rect
			(at -13.335 0.824992 90)
			(size 0.6604 2.0574)
			(layers "F.Cu" "F.Mask" "F.Paste")
			(net "Net_1189")
		)
		(pad "S4" smd rect
			(at -12.065 0.824992 90)
			(size 0.6604 2.0574)
			(layers "F.Cu" "F.Mask" "F.Paste")
			(net "GND")
		)
		(pad "S5" smd rect
			(at -10.795 0.824992 90)
			(size 0.6604 2.0574)
			(layers "F.Cu" "F.Mask" "F.Paste")
			(net "Net_1188")
		)
		(pad "S6" smd rect
			(at -9.525 0.824992 90)
			(size 0.6604 2.0574)
			(layers "F.Cu" "F.Mask" "F.Paste")
			(net "Net_1187")
		)
		(pad "S7" smd rect
			(at -8.255 0.824992 90)
			(size 0.6604 2.0574)
			(layers "F.Cu" "F.Mask" "F.Paste")
			(net "GND")
		)
		(pad "S8" smd rect
			(at -7.480046 -1.949958 90)
			(size 0.508 2.0066)
			(layers "F.Cu" "F.Mask" "F.Paste")
			(net "GND")
		)
		(pad "S9" smd rect
			(at -6.679946 -1.949958 90)
			(size 0.508 2.0066)
			(layers "F.Cu" "F.Mask" "F.Paste")
			(net "Net_1185")
		)
		(pad "S10" smd rect
			(at -5.8801 -1.949958 90)
			(size 0.508 2.0066)
			(layers "F.Cu" "F.Mask" "F.Paste")
			(net "Net_1184")
		)
		(pad "S11" smd rect
			(at -5.08 -1.949958 90)
			(size 0.508 2.0066)
			(layers "F.Cu" "F.Mask" "F.Paste")
			(net "GND")
		)
		(pad "S12" smd rect
			(at -4.2799 -1.949958 90)
			(size 0.508 2.0066)
			(layers "F.Cu" "F.Mask" "F.Paste")
			(net "Net_1183")
		)
		(pad "S13" smd rect
			(at -3.480054 -1.949958 90)
			(size 0.508 2.0066)
			(layers "F.Cu" "F.Mask" "F.Paste")
			(net "Net_1178")
		)
		(pad "S14" smd rect
			(at -2.679954 -1.949958 90)
			(size 0.508 2.0066)
			(layers "F.Cu" "F.Mask" "F.Paste")
			(net "GND")
		)
		(pad "S15" smd rect
			(at -1.880108 -1.949958 90)
			(size 0.508 2.0066)
			(layers "F.Cu" "F.Mask" "F.Paste")
			(net "Net_1177")
		)
		(pad "S16" smd rect
			(at -1.080008 -1.949958 90)
			(size 0.508 2.0066)
			(layers "F.Cu" "F.Mask" "F.Paste")
			(net "GND")
		)
		(pad "S17" smd rect
			(at -0.279908 -1.949958 90)
			(size 0.508 2.0066)
			(layers "F.Cu" "F.Mask" "F.Paste")
			(net "PE_TX2_DR3_N")
		)
		(pad "S18" smd rect
			(at 0.519938 -1.949958 90)
			(size 0.508 2.0066)
			(layers "F.Cu" "F.Mask" "F.Paste")
			(net "PE_TX2_DR3_P")
		)
		(pad "S19" smd rect
			(at 1.320038 -1.949958 90)
			(size 0.508 2.0066)
			(layers "F.Cu" "F.Mask" "F.Paste")
			(net "GND")
		)
		(pad "S20" smd rect
			(at 2.119884 -1.949958 90)
			(size 0.508 2.0066)
			(layers "F.Cu" "F.Mask" "F.Paste")
			(net "PE_RX2_DR3_N")
		)
		(pad "S21" smd rect
			(at 2.919984 -1.949958 90)
			(size 0.508 2.0066)
			(layers "F.Cu" "F.Mask" "F.Paste")
			(net "PE_RX2_DR3_P")
		)
		(pad "S22" smd rect
			(at 3.720084 -1.949958 90)
			(size 0.508 2.0066)
			(layers "F.Cu" "F.Mask" "F.Paste")
			(net "GND")
		)
		(pad "S23" smd rect
			(at 4.51993 -1.949958 90)
			(size 0.508 2.0066)
			(layers "F.Cu" "F.Mask" "F.Paste")
			(net "PE_TX3_DR3_N")
		)
		(pad "S24" smd rect
			(at 5.32003 -1.949958 90)
			(size 0.508 2.0066)
			(layers "F.Cu" "F.Mask" "F.Paste")
			(net "PE_TX3_DR3_P")
		)
		(pad "S25" smd rect
			(at 6.119876 -1.949958 90)
			(size 0.508 2.0066)
			(layers "F.Cu" "F.Mask" "F.Paste")
			(net "GND")
		)
		(pad "S26" smd rect
			(at 6.919976 -1.949958 90)
			(size 0.508 2.0066)
			(layers "F.Cu" "F.Mask" "F.Paste")
			(net "PE_RX3_DR3_N")
		)
		(pad "S27" smd rect
			(at 7.720076 -1.949958 90)
			(size 0.508 2.0066)
			(layers "F.Cu" "F.Mask" "F.Paste")
			(net "PE_RX3_DR3_P")
		)
		(pad "S28" smd rect
			(at 8.519922 -1.949958 90)
			(size 0.508 2.0066)
			(layers "F.Cu" "F.Mask" "F.Paste")
			(net "GND")
		)
		(zone
			(layers "F.Cu" "B.Cu" "In1.Cu" "In2.Cu" "In3.Cu" "In4.Cu" "In5.Cu" "In6.Cu")
			(hatch none 0.5)
			(connect_pads
				(clearance 0)
			)
			(min_thickness 0.25)
			(keepout
				(tracks not_allowed)
				(vias allowed)
				(pads allowed)
				(copperpour not_allowed)
				(footprints allowed)
			)
			(placement
				(enabled no)
				(sheetname "")
			)
			(fill
				(thermal_gap 0.5)
				(thermal_bridge_width 0.5)
				(island_removal_mode 0)
			)
			(polygon
				(pts
					(arc
						(start 227.381816 -189.669928)
						(mid 224.918016 -189.669928)
						(end 227.381816 -189.669928)
					)
				)
			)
		)
		(zone
			(layers "F.Cu" "B.Cu" "In1.Cu" "In2.Cu" "In3.Cu" "In4.Cu" "In5.Cu" "In6.Cu")
			(hatch none 0.5)
			(connect_pads
				(clearance 0)
			)
			(min_thickness 0.25)
			(keepout
				(tracks not_allowed)
				(vias allowed)
				(pads allowed)
				(copperpour not_allowed)
				(footprints allowed)
			)
			(placement
				(enabled no)
				(sheetname "")
			)
			(fill
				(thermal_gap 0.5)
				(thermal_bridge_width 0.5)
				(island_removal_mode 0)
			)
			(polygon
				(pts
					(arc
						(start 227.381816 -151.670004)
						(mid 224.918016 -151.670004)
						(end 227.381816 -151.670004)
					)
				)
			)
		)
	)
)
